# GMSL Deserializer — KiCad project settings (.kicad_pro: net classes, design rules, text variables)
{
  "board": {
    "3dviewports": [],
    "design_settings": {
      "defaults": {
        "apply_defaults_to_fp_fields": false,
        "apply_defaults_to_fp_shapes": false,
        "apply_defaults_to_fp_text": false,
        "board_outline_line_width": 0.05,
        "copper_line_width": 0.2,
        "copper_text_italic": false,
        "copper_text_size_h": 1.5,
        "copper_text_size_v": 1.5,
        "copper_text_thickness": 0.3,
        "copper_text_upright": false,
        "courtyard_line_width": 0.05,
        "dimension_precision": 4,
        "dimension_units": 3,
        "dimensions": {
          "arrow_length": 1270000,
          "extension_offset": 500000,
          "keep_text_aligned": true,
          "suppress_zeroes": false,
          "text_position": 0,
          "units_format": 1
        },
        "fab_line_width": 0.1,
        "fab_text_italic": false,
        "fab_text_size_h": 1.0,
        "fab_text_size_v": 1.0,
        "fab_text_thickness": 0.15,
        "fab_text_upright": false,
        "other_line_width": 0.1,
        "other_text_italic": false,
        "other_text_size_h": 1.0,
        "other_text_size_v": 1.0,
        "other_text_thickness": 0.15,
        "other_text_upright": false,
        "pads": {
          "drill": 0.0,
          "height": 2.1,
          "width": 5.2
        },
        "silk_line_width": 0.12,
        "silk_text_italic": false,
        "silk_text_size_h": 1.0,
        "silk_text_size_v": 1.0,
        "silk_text_thickness": 0.15,
        "silk_text_upright": false,
        "zones": {
          "45_degree_only": false,
          "min_clearance": 0.2
        }
      },
      "diff_pair_dimensions": [
        {
          "gap": 0.0,
          "via_gap": 0.0,
          "width": 0.0
        },
        {
          "gap": 0.279,
          "via_gap": 0.321,
          "width": 0.186
        },
        {
          "gap": 0.196,
          "via_gap": 0.321,
          "width": 0.187
        }
      ],
      "drc_exclusions": [],
      "meta": {
        "version": 2
      },
      "rule_severities": {
        "annular_width": "error",
        "clearance": "error",
        "connection_width": "warning",
        "copper_edge_clearance": "error",
        "copper_sliver": "warning",
        "courtyards_overlap": "error",
        "creepage": "error",
        "diff_pair_gap_out_of_range": "error",
        "diff_pair_uncoupled_length_too_long": "error",
        "drill_out_of_range": "error",
        "duplicate_footprints": "warning",
        "extra_footprint": "warning",
        "footprint": "error",
        "footprint_filters_mismatch": "ignore",
        "footprint_symbol_mismatch": "warning",
        "footprint_type_mismatch": "ignore",
        "hole_clearance": "error",
        "hole_near_hole": "error",
        "hole_to_hole": "error",
        "holes_co_located": "warning",
        "invalid_outline": "error",
        "isolated_copper": "warning",
        "item_on_disabled_layer": "error",
        "items_not_allowed": "error",
        "length_out_of_range": "error",
        "lib_footprint_issues": "warning",
        "lib_footprint_mismatch": "warning",
        "malformed_courtyard": "error",
        "microvia_drill_out_of_range": "error",
        "mirrored_text_on_front_layer": "warning",
        "missing_courtyard": "warning",
        "missing_footprint": "warning",
        "net_conflict": "warning",
        "nonmirrored_text_on_back_layer": "warning",
        "npth_inside_courtyard": "warning",
        "padstack": "error",
        "pth_inside_courtyard": "warning",
        "shorting_items": "error",
        "silk_edge_clearance": "warning",
        "silk_over_copper": "warning",
        "silk_overlap": "warning",
        "skew_out_of_range": "error",
        "solder_mask_bridge": "error",
        "starved_thermal": "error",
        "text_height": "warning",
        "text_on_edge_cuts": "error",
        "text_thickness": "warning",
        "through_hole_pad_without_hole": "error",
        "too_many_vias": "error",
        "track_angle": "error",
        "track_dangling": "warning",
        "track_segment_length": "error",
        "track_width": "error",
        "tracks_crossing": "error",
        "unconnected_items": "error",
        "unresolved_variable": "error",
        "via_dangling": "warning",
        "zones_intersect": "error"
      },
      "rules": {
        "allow_blind_buried_vias": false,
        "allow_microvias": false,
        "max_error": 0.005,
        "min_clearance": 0.0,
        "min_connection": 0.0,
        "min_copper_edge_clearance": 0.127,
        "min_groove_width": 0.0,
        "min_hole_clearance": 0.25,
        "min_hole_to_hole": 0.25,
        "min_microvia_diameter": 0.2,
        "min_microvia_drill": 0.1,
        "min_resolved_spokes": 2,
        "min_silk_clearance": 0.0,
        "min_text_height": 0.6,
        "min_text_thickness": 0.08,
        "min_through_hole_diameter": 0.25,
        "min_track_width": 0.125,
        "min_via_annular_width": 0.05,
        "min_via_diameter": 0.6,
        "solder_mask_clearance": 0.0,
        "solder_mask_min_width": 0.0,
        "solder_mask_to_copper_clearance": 0.0,
        "use_height_for_length_calcs": true
      },
      "teardrop_options": [
        {
          "td_onpthpad": true,
          "td_onroundshapesonly": false,
          "td_onsmdpad": true,
          "td_ontrackend": false,
          "td_onvia": true
        }
      ],
      "teardrop_parameters": [
        {
          "td_allow_use_two_tracks": true,
          "td_curve_segcount": 0,
          "td_height_ratio": 1.0,
          "td_length_ratio": 0.5,
          "td_maxheight": 2.0,
          "td_maxlen": 1.0,
          "td_on_pad_in_zone": false,
          "td_target_name": "td_round_shape",
          "td_width_to_size_filter_ratio": 0.9
        },
        {
          "td_allow_use_two_tracks": true,
          "td_curve_segcount": 0,
          "td_height_ratio": 1.0,
          "td_length_ratio": 0.5,
          "td_maxheight": 2.0,
          "td_maxlen": 1.0,
          "td_on_pad_in_zone": false,
          "td_target_name": "td_rect_shape",
          "td_width_to_size_filter_ratio": 0.9
        },
        {
          "td_allow_use_two_tracks": true,
          "td_curve_segcount": 0,
          "td_height_ratio": 1.0,
          "td_length_ratio": 0.5,
          "td_maxheight": 2.0,
          "td_maxlen": 1.0,
          "td_on_pad_in_zone": false,
          "td_target_name": "td_track_end",
          "td_width_to_size_filter_ratio": 0.9
        }
      ],
      "track_widths": [
        0.0,
        0.187,
        0.3,
        0.5,
        0.8
      ],
      "tuning_pattern_settings": {
        "diff_pair_defaults": {
          "corner_radius_percentage": 80,
          "corner_style": 1,
          "max_amplitude": 1.0,
          "min_amplitude": 0.2,
          "single_sided": false,
          "spacing": 1.0
        },
        "diff_pair_skew_defaults": {
          "corner_radius_percentage": 80,
          "corner_style": 1,
          "max_amplitude": 1.0,
          "min_amplitude": 0.2,
          "single_sided": false,
          "spacing": 0.6
        },
        "single_track_defaults": {
          "corner_radius_percentage": 80,
          "corner_style": 1,
          "max_amplitude": 1.0,
          "min_amplitude": 0.2,
          "single_sided": false,
          "spacing": 0.6
        }
      },
      "via_dimensions": [
        {
          "diameter": 0.0,
          "drill": 0.0
        },
        {
          "diameter": 0.55,
          "drill": 0.25
        }
      ],
      "zones_allow_external_fillets": false,
      "zones_use_no_outline": true
    },
    "ipc2581": {
      "dist": "",
      "distpn": "",
      "internal_id": "",
      "mfg": "",
      "mpn": ""
    },
    "layer_pairs": [],
    "layer_presets": [],
    "viewports": []
  },
  "boards": [],
  "cvpcb": {
    "equivalence_files": []
  },
  "erc": {
    "erc_exclusions": [],
    "meta": {
      "version": 0
    },
    "pin_map": [
      [
        0,
        0,
        0,
        0,
        0,
        0,
        1,
        0,
        0,
        0,
        0,
        2
      ],
      [
        0,
        2,
        0,
        1,
        0,
        0,
        1,
        0,
        2,
        2,
        2,
        2
      ],
      [
        0,
        0,
        0,
        0,
        0,
        0,
        1,
        0,
        1,
        0,
        1,
        2
      ],
      [
        0,
        1,
        0,
        0,
        0,
        0,
        1,
        1,
        2,
        1,
        1,
        2
      ],
      [
        0,
        0,
        0,
        0,
        0,
        0,
        1,
        0,
        0,
        0,
        0,
        2
      ],
      [
        0,
        0,
        0,
        0,
        0,
        0,
        0,
        0,
        0,
        0,
        0,
        2
      ],
      [
        1,
        1,
        1,
        1,
        1,
        0,
        1,
        1,
        1,
        1,
        1,
        2
      ],
      [
        0,
        0,
        0,
        1,
        0,
        0,
        1,
        0,
        0,
        0,
        0,
        2
      ],
      [
        0,
        2,
        1,
        2,
        0,
        0,
        1,
        0,
        2,
        2,
        2,
        2
      ],
      [
        0,
        2,
        0,
        1,
        0,
        0,
        1,
        0,
        2,
        0,
        0,
        2
      ],
      [
        0,
        2,
        1,
        1,
        0,
        0,
        1,
        0,
        2,
        0,
        0,
        2
      ],
      [
        2,
        2,
        2,
        2,
        2,
        2,
        2,
        2,
        2,
        2,
        2,
        2
      ]
    ],
    "rule_severities": {
      "bus_definition_conflict": "error",
      "bus_entry_needed": "error",
      "bus_to_bus_conflict": "error",
      "bus_to_net_conflict": "error",
      "conflicting_netclasses": "error",
      "different_unit_footprint": "error",
      "different_unit_net": "error",
      "duplicate_reference": "error",
      "duplicate_sheet_names": "error",
      "endpoint_off_grid": "warning",
      "extra_units": "error",
      "footprint_filter": "ignore",
      "footprint_link_issues": "warning",
      "four_way_junction": "ignore",
      "global_label_dangling": "warning",
      "hier_label_mismatch": "error",
      "label_dangling": "error",
      "label_multiple_wires": "warning",
      "lib_symbol_issues": "warning",
      "lib_symbol_mismatch": "warning",
      "missing_bidi_pin": "warning",
      "missing_input_pin": "warning",
      "missing_power_pin": "error",
      "missing_unit": "warning",
      "multiple_net_names": "warning",
      "net_not_bus_member": "warning",
      "no_connect_connected": "error",
      "no_connect_dangling": "warning",
      "pin_not_connected": "error",
      "pin_not_driven": "error",
      "pin_to_pin": "ignore",
      "power_pin_not_driven": "error",
      "same_local_global_label": "warning",
      "similar_label_and_power": "warning",
      "similar_labels": "warning",
      "similar_power": "warning",
      "simulation_model_issue": "ignore",
      "single_global_label": "ignore",
      "unannotated": "error",
      "unconnected_wire_endpoint": "warning",
      "undefined_netclass": "error",
      "unit_value_mismatch": "error",
      "unresolved_variable": "error",
      "wire_dangling": "error"
    }
  },
  "libraries": {
    "pinned_footprint_libs": [],
    "pinned_symbol_libs": []
  },
  "meta": {
    "filename": "gmsl-deserializer.kicad_pro",
    "version": 3
  },
  "net_settings": {
    "classes": [
      {
        "bus_width": 12,
        "clearance": 0.125,
        "diff_pair_gap": 0.125,
        "diff_pair_via_gap": 0.25,
        "diff_pair_width": 0.125,
        "line_style": 0,
        "microvia_diameter": 0.3,
        "microvia_drill": 0.1,
        "name": "Default",
        "pcb_color": "rgba(0, 0, 0, 0.000)",
        "priority": 2147483647,
        "schematic_color": "rgba(0, 0, 0, 0.000)",
        "track_width": 0.125,
        "via_diameter": 0.6,
        "via_drill": 0.35,
        "wire_width": 6
      },
      {
        "bus_width": 12,
        "clearance": 0.125,
        "diff_pair_gap": 0.125,
        "diff_pair_width": 0.125,
        "line_style": 0,
        "microvia_diameter": 0.3,
        "microvia_drill": 0.1,
        "name": "50Ohm-se_GMSL",
        "pcb_color": "rgba(0, 0, 0, 0.000)",
        "priority": 0,
        "schematic_color": "rgba(0, 0, 0, 0.000)",
        "track_width": 0.187,
        "via_diameter": 0.6,
        "via_drill": 0.35,
        "wire_width": 6
      },
      {
        "bus_width": 12,
        "clearance": 0.125,
        "diff_pair_gap": 0.125,
        "diff_pair_width": 0.155,
        "line_style": 0,
        "microvia_diameter": 0.3,
        "microvia_drill": 0.1,
        "name": "90Ohm-diff_CSI",
        "pcb_color": "rgba(0, 0, 0, 0.000)",
        "priority": 1,
        "schematic_color": "rgba(0, 0, 0, 0.000)",
        "track_width": 0.215,
        "via_diameter": 0.6,
        "via_drill": 0.35,
        "wire_width": 6
      }
    ],
    "meta": {
      "version": 4
    },
    "net_colors": null,
    "netclass_assignments": null,
    "netclass_patterns": [
      {
        "netclass": "50Ohm-se_GMSL",
        "pattern": "/Connectors/PoCA"
      },
      {
        "netclass": "50Ohm-se_GMSL",
        "pattern": "/Connectors/PoCB"
      },
      {
        "netclass": "50Ohm-se_GMSL",
        "pattern": "/Connectors/PoCC"
      },
      {
        "netclass": "50Ohm-se_GMSL",
        "pattern": "/Connectors/PoCD"
      },
      {
        "netclass": "50Ohm-se_GMSL",
        "pattern": "/Deserializer/SIOA_N"
      },
      {
        "netclass": "50Ohm-se_GMSL",
        "pattern": "/Deserializer/SIOA_P"
      },
      {
        "netclass": "50Ohm-se_GMSL",
        "pattern": "/Deserializer/SIOB_N"
      },
      {
        "netclass": "50Ohm-se_GMSL",
        "pattern": "/Deserializer/SIOB_P"
      },
      {
        "netclass": "50Ohm-se_GMSL",
        "pattern": "/Deserializer/SIOC_N"
      },
      {
        "netclass": "50Ohm-se_GMSL",
        "pattern": "/Deserializer/SIOC_P"
      },
      {
        "netclass": "50Ohm-se_GMSL",
        "pattern": "/Deserializer/SIOD_N"
      },
      {
        "netclass": "50Ohm-se_GMSL",
        "pattern": "/Deserializer/SIOD_P"
      },
      {
        "netclass": "90Ohm-diff_CSI",
        "pattern": "/Connectors/CSI0.CLK_N"
      },
      {
        "netclass": "90Ohm-diff_CSI",
        "pattern": "/Connectors/CSI0.CLK_P"
      },
      {
        "netclass": "90Ohm-diff_CSI",
        "pattern": "/Connectors/CSI0.D0_N"
      },
      {
        "netclass": "90Ohm-diff_CSI",
        "pattern": "/Connectors/CSI0.D0_P"
      },
      {
        "netclass": "90Ohm-diff_CSI",
        "pattern": "/Connectors/CSI0.D1_N"
      },
      {
        "netclass": "90Ohm-diff_CSI",
        "pattern": "/Connectors/CSI0.D1_P"
      },
      {
        "netclass": "90Ohm-diff_CSI",
        "pattern": "/Connectors/CSI0.D2_N"
      },
      {
        "netclass": "90Ohm-diff_CSI",
        "pattern": "/Connectors/CSI0.D2_P"
      },
      {
        "netclass": "90Ohm-diff_CSI",
        "pattern": "/Connectors/CSI0.D3_N"
      },
      {
        "netclass": "90Ohm-diff_CSI",
        "pattern": "/Connectors/CSI0.D3_P"
      },
      {
        "netclass": "90Ohm-diff_CSI",
        "pattern": "/Connectors/CSI1.CLK_N"
      },
      {
        "netclass": "90Ohm-diff_CSI",
        "pattern": "/Connectors/CSI1.CLK_P"
      },
      {
        "netclass": "90Ohm-diff_CSI",
        "pattern": "/Connectors/CSI1.D0_N"
      },
      {
        "netclass": "90Ohm-diff_CSI",
        "pattern": "/Connectors/CSI1.D0_P"
      },
      {
        "netclass": "90Ohm-diff_CSI",
        "pattern": "/Connectors/CSI1.D1_N"
      },
      {
        "netclass": "90Ohm-diff_CSI",
        "pattern": "/Connectors/CSI1.D1_P"
      },
      {
        "netclass": "90Ohm-diff_CSI",
        "pattern": "/Connectors/CSI1.D2_N"
      },
      {
        "netclass": "90Ohm-diff_CSI",
        "pattern": "/Connectors/CSI1.D2_P"
      },
      {
        "netclass": "90Ohm-diff_CSI",
        "pattern": "/Connectors/CSI1.D3_N"
      },
      {
        "netclass": "90Ohm-diff_CSI",
        "pattern": "/Connectors/CSI1.D3_P"
      }
    ]
  },
  "pcbnew": {
    "last_paths": {
      "gencad": "",
      "idf": "",
      "netlist": "",
      "plot": "",
      "pos_files": "",
      "specctra_dsn": "",
      "step": "",
      "svg": "",
      "vrml": ""
    },
    "page_layout_descr_file": ""
  },
  "schematic": {
    "annotate_start_num": 0,
    "bom_export_filename": "",
    "bom_fmt_presets": [],
    "bom_fmt_settings": {
      "field_delimiter": ",",
      "keep_line_breaks": false,
      "keep_tabs": false,
      "name": "CSV",
      "ref_delimiter": ",",
      "ref_range_delimiter": "",
      "string_delimiter": "\""
    },
    "bom_presets": [],
    "bom_settings": {
      "exclude_dnp": false,
      "fields_ordered": [
        {
          "group_by": false,
          "label": "Reference",
          "name": "Reference",
          "show": true
        },
        {
          "group_by": true,
          "label": "Value",
          "name": "Value",
          "show": true
        },
        {
          "group_by": false,
          "label": "Datasheet",
          "name": "Datasheet",
          "show": true
        },
        {
          "group_by": false,
          "label": "Footprint",
          "name": "Footprint",
          "show": true
        },
        {
          "group_by": false,
          "label": "Qty",
          "name": "${QUANTITY}",
          "show": true
        },
        {
          "group_by": true,
          "label": "DNP",
          "name": "${DNP}",
          "show": true
        }
      ],
      "filter_string": "",
      "group_symbols": true,
      "include_excluded_from_bom": false,
      "name": "Grouped By Value",
      "sort_asc": true,
      "sort_field": "Reference"
    },
    "connection_grid_size": 50.0,
    "drawing": {
      "dashed_lines_dash_length_ratio": 12.0,
      "dashed_lines_gap_length_ratio": 3.0,
      "default_line_thickness": 6.0,
      "default_text_size": 50.0,
      "field_names": [],
      "intersheets_ref_own_page": false,
      "intersheets_ref_prefix": "",
      "intersheets_ref_short": false,
      "intersheets_ref_show": false,
      "intersheets_ref_suffix": "",
      "junction_size_choice": 3,
      "label_size_ratio": 0.375,
      "operating_point_overlay_i_precision": 3,
      "operating_point_overlay_i_range": "~A",
      "operating_point_overlay_v_precision": 3,
      "operating_point_overlay_v_range": "~V",
      "overbar_offset_ratio": 1.23,
      "pin_symbol_size": 25.0,
      "text_offset_ratio": 0.15
    },
    "legacy_lib_dir": "",
    "legacy_lib_list": [],
    "meta": {
      "version": 1
    },
    "net_format_name": "",
    "ngspice": {
      "fix_include_paths": true,
      "fix_passive_vals": false,
      "meta": {
        "version": 0
      },
      "model_mode": 0,
      "workbook_filename": ""
    },
    "page_layout_descr_file": "",
    "plot_directory": "",
    "space_save_all_events": true,
    "spice_adjust_passive_values": false,
    "spice_current_sheet_as_root": false,
    "spice_external_command": "spice \"%I\"",
    "spice_model_current_sheet_as_root": true,
    "spice_save_all_currents": false,
    "spice_save_all_dissipations": false,
    "spice_save_all_voltages": false,
    "subpart_first_id": 65,
    "subpart_id_separator": 0
  },
  "sheets": [
    [
      "",
      "Root"
    ],
    [
      "",
      "Connectors"
    ],
    [
      "",
      "Power"
    ],
    [
      "",
      "Deserializer"
    ]
  ],
  "text_variables": {}
}
